(kicad_pcb
	(version 20260206)
	(generator "pcbnew")
	(generator_version "10.0")
	(general
		(thickness 1.6)
		(legacy_teardrops no)
	)
	(paper "A4")
	(title_block
		(title "Wiwynn_Tioga_Pass_MB.brd")
		(comment 1 "Tioga Pass / footprint 2254 of 4770 (U5D1), pads 2519-2626 of 3647")
	)
	(layers
		(0 "F.Cu" signal "TOP")
		(4 "In1.Cu" signal "L2GND")
		(6 "In2.Cu" signal "L3")
		(8 "In3.Cu" signal "L4GND")
		(10 "In4.Cu" signal "L5")
		(12 "In5.Cu" signal "L6GND")
		(14 "In6.Cu" signal "L7VCC")
		(16 "In7.Cu" signal "L8VCC")
		(18 "In8.Cu" signal "L9GND")
		(20 "In9.Cu" signal "L10")
		(22 "In10.Cu" signal "L11GND")
		(24 "In11.Cu" signal "L12")
		(26 "In12.Cu" signal "L13GND")
		(2 "B.Cu" signal "BOTTOM")
		(9 "F.Adhes" user "F.Adhesive")
		(11 "B.Adhes" user "B.Adhesive")
		(13 "F.Paste" user "Package Geometry/Pastemask Top")
		(15 "B.Paste" user "Package Geometry/Pastemask Bottom")
		(5 "F.SilkS" user "Ref Des/Silkscreen Top")
		(7 "B.SilkS" user "Ref Des/Silkscreen Bottom")
		(1 "F.Mask" user "Board Geometry/Soldermask Top")
		(3 "B.Mask" user "Board Geometry/Soldermask Bottom")
		(17 "Dwgs.User" user "User.Drawings")
		(19 "Cmts.User" user "User.Comments")
		(21 "Eco1.User" user "User.Eco1")
		(23 "Eco2.User" user "User.Eco2")
		(25 "Edge.Cuts" user "Board Geometry/Outline")
		(27 "Margin" user)
		(31 "F.CrtYd" user "Package Geometry/Place Bound Top")
		(29 "B.CrtYd" user "Package Geometry/Place Bound Bottom")
		(35 "F.Fab" user "Ref Des/Assembly Top")
		(33 "B.Fab" user "Ref Des/Assembly Bottom")
	)
	(footprint ""
		(layer "F.Cu")
		(at 270.000222 -76.550012 180)
		(property "Reference" "U5D1"
			(at 19.124422 31.601918 0)
			(unlocked yes)
			(layer "F.SilkS")
			(effects
				(font
					(size 0.7874 0.5842)
					(thickness 0.1524)
				)
			)
		)
		(property "Value" ""
			(at 0 0 180)
			(layer "F.Fab")
			(effects
				(font
					(size 1.27 1.27)
				)
			)
		)
		(duplicate_pad_numbers_are_jumpers no)
		(pad "DP75" smd circle
			(at 27.806904 19.159474)
			(size 0.4318 0.4318)
			(layers "F.Cu" "F.Mask" "F.Paste")
			(net "M_D_DQS_DN<12>")
		)
		(pad "DP77" smd circle
			(at 29.523944 19.159474)
			(size 0.4318 0.4318)
			(layers "F.Cu" "F.Mask" "F.Paste")
			(net "M_D_DQ<28>")
		)
		(pad "DP79" smd circle
			(at 31.240984 19.159474)
			(size 0.4318 0.4318)
			(layers "F.Cu" "F.Mask" "F.Paste")
			(net "M_D_DQS_DP<11>")
		)
		(pad "DP81" smd circle
			(at 32.958024 19.159474)
			(size 0.4318 0.4318)
			(layers "F.Cu" "F.Mask" "F.Paste")
			(net "GND")
		)
		(pad "DP83" smd circle
			(at 34.675064 19.159474)
			(size 0.4318 0.4318)
			(layers "F.Cu" "F.Mask" "F.Paste")
			(net "GND")
		)
		(pad "DP85" smd custom
			(at 36.392104 19.159474 270)
			(size 0.10795 0.10795)
			(layers "F.Cu" "F.Mask" "F.Paste")
			(net "M_D_DQS_DP<1>")
			(options
				(clearance outline)
				(anchor circle)
			)
			(primitives
				(gr_poly
					(pts
						(arc
							(start 0.2159 -0.0381)
							(mid 0 -0.254)
							(end -0.2159 -0.0381)
						)
						(arc
							(start -0.2159 0.0381)
							(mid 0 0.254)
							(end 0.2159 0.0381)
						)
					)
					(width 0)
					(fill yes)
				)
			)
		)
		(pad "DR2" smd custom
			(at -36.392104 21.455126 90)
			(size 0.10795 0.10795)
			(layers "F.Cu" "F.Mask" "F.Paste")
			(net "PVCCIO_CPU0")
			(options
				(clearance outline)
				(anchor circle)
			)
			(primitives
				(gr_poly
					(pts
						(arc
							(start 0.2159 -0.0381)
							(mid 0 -0.254)
							(end -0.2159 -0.0381)
						)
						(arc
							(start -0.2159 0.0381)
							(mid 0 0.254)
							(end 0.2159 0.0381)
						)
					)
					(width 0)
					(fill yes)
				)
			)
		)
		(pad "DR4" smd circle
			(at -34.675064 21.455126)
			(size 0.4318 0.4318)
			(layers "F.Cu" "F.Mask" "F.Paste")
			(net "P3E_CPU0_PE1_PCH_TXP<8>")
		)
		(pad "DR6" smd circle
			(at -32.958024 21.455126)
			(size 0.4318 0.4318)
			(layers "F.Cu" "F.Mask" "F.Paste")
			(net "GND")
		)
		(pad "DR8" smd circle
			(at -31.240984 21.455126)
			(size 0.4318 0.4318)
			(layers "F.Cu" "F.Mask" "F.Paste")
			(net "P3E_CPU0_PE3_OCP_TXN<7>")
		)
		(pad "DR10" smd circle
			(at -29.523944 21.455126)
			(size 0.4318 0.4318)
			(layers "F.Cu" "F.Mask" "F.Paste")
			(net "PVCCIO_CPU0")
		)
		(pad "DR12" smd circle
			(at -27.806904 21.455126)
			(size 0.4318 0.4318)
			(layers "F.Cu" "F.Mask" "F.Paste")
			(net "P3E_CPU0_PE1_PCH_RXP<10>")
		)
		(pad "DR14" smd circle
			(at -26.090118 21.455126)
			(size 0.4318 0.4318)
			(layers "F.Cu" "F.Mask" "F.Paste")
			(net "P3E_CPU0_PE3_OCP_RXN<5>")
		)
		(pad "DR16" smd circle
			(at -24.373078 21.455126)
			(size 0.4318 0.4318)
			(layers "F.Cu" "F.Mask" "F.Paste")
			(net "P3E_CPU0_PE3_OCP_RXN<4>")
		)
		(pad "DR18" smd circle
			(at -22.656038 21.455126)
			(size 0.4318 0.4318)
			(layers "F.Cu" "F.Mask" "F.Paste")
			(net "P3E_CPU0_PE3_OCP_RXP<3>")
		)
		(pad "DR20" smd circle
			(at -20.938998 21.455126)
			(size 0.4318 0.4318)
			(layers "F.Cu" "F.Mask" "F.Paste")
			(net "GND")
		)
		(pad "DR22" smd circle
			(at -19.221958 21.455126)
			(size 0.4318 0.4318)
			(layers "F.Cu" "F.Mask" "F.Paste")
			(net "GND")
		)
		(pad "DR24" smd circle
			(at -17.504918 21.455126)
			(size 0.4318 0.4318)
			(layers "F.Cu" "F.Mask" "F.Paste")
			(net "GND")
		)
		(pad "DR26" smd circle
			(at -15.787878 21.455126)
			(size 0.4318 0.4318)
			(layers "F.Cu" "F.Mask" "F.Paste")
			(net "GND")
		)
		(pad "DR28" smd circle
			(at -14.071092 21.455126)
			(size 0.4318 0.4318)
			(layers "F.Cu" "F.Mask" "F.Paste")
			(net "GND")
		)
		(pad "DR30" smd circle
			(at -12.354052 21.455126)
			(size 0.4318 0.4318)
			(layers "F.Cu" "F.Mask" "F.Paste")
			(net "GND")
		)
		(pad "DR32" smd circle
			(at -10.637012 21.455126)
			(size 0.4318 0.4318)
			(layers "F.Cu" "F.Mask" "F.Paste")
			(net "GND")
		)
		(pad "DR34" smd circle
			(at -8.919972 21.455126)
			(size 0.4318 0.4318)
			(layers "F.Cu" "F.Mask" "F.Paste")
			(net "GND")
		)
		(pad "DR36" smd circle
			(at -7.202932 21.455126)
			(size 0.4318 0.4318)
			(layers "F.Cu" "F.Mask" "F.Paste")
			(net "GND")
		)
		(pad "DR38" smd circle
			(at -5.485892 21.455126)
			(size 0.4318 0.4318)
			(layers "F.Cu" "F.Mask" "F.Paste")
			(net "GND")
		)
		(pad "DR40" smd circle
			(at -3.769106 21.455126)
			(size 0.4318 0.4318)
			(layers "F.Cu" "F.Mask" "F.Paste")
			(net "GND")
		)
		(pad "DR42" smd circle
			(at -2.052066 21.455126)
			(size 0.4318 0.4318)
			(layers "F.Cu" "F.Mask" "F.Paste")
			(net "GND")
		)
		(pad "DR44" smd circle
			(at 1.193546 19.655028)
			(size 0.508 0.508)
			(layers "F.Cu" "F.Mask" "F.Paste")
			(net "TP_CPU0_RSVD_28")
		)
		(pad "DR46" smd circle
			(at 2.910586 19.655028)
			(size 0.4318 0.4318)
			(layers "F.Cu" "F.Mask" "F.Paste")
			(net "M_E_CS_N<2>")
		)
		(pad "DR48" smd circle
			(at 4.627626 19.655028)
			(size 0.4318 0.4318)
			(layers "F.Cu" "F.Mask" "F.Paste")
			(net "M_E_MA<17>")
		)
		(pad "DR50" smd circle
			(at 6.344412 19.655028)
			(size 0.4318 0.4318)
			(layers "F.Cu" "F.Mask" "F.Paste")
			(net "M_E_ODT<0>")
		)
		(pad "DR52" smd circle
			(at 8.061452 19.655028)
			(size 0.4318 0.4318)
			(layers "F.Cu" "F.Mask" "F.Paste")
			(net "M_E_MA<15>")
		)
		(pad "DR54" smd circle
			(at 9.778492 19.655028)
			(size 0.4318 0.4318)
			(layers "F.Cu" "F.Mask" "F.Paste")
			(net "M_E_CLK_DN<1>")
		)
		(pad "DR56" smd circle
			(at 11.495532 19.655028)
			(size 0.4318 0.4318)
			(layers "F.Cu" "F.Mask" "F.Paste")
			(net "M_E_CLK_DP<3>")
		)
		(pad "DR58" smd circle
			(at 13.212572 19.655028)
			(size 0.4318 0.4318)
			(layers "F.Cu" "F.Mask" "F.Paste")
			(net "M_E_MA<3>")
		)
		(pad "DR60" smd circle
			(at 14.929612 19.655028)
			(size 0.4318 0.4318)
			(layers "F.Cu" "F.Mask" "F.Paste")
			(net "M_E_MA<11>")
		)
		(pad "DR62" smd circle
			(at 16.646398 19.655028)
			(size 0.4318 0.4318)
			(layers "F.Cu" "F.Mask" "F.Paste")
			(net "M_E_ACT_N")
		)
		(pad "DR64" smd circle
			(at 18.363438 19.655028)
			(size 0.4318 0.4318)
			(layers "F.Cu" "F.Mask" "F.Paste")
			(net "M_E_CKE<3>")
		)
		(pad "DR66" smd circle
			(at 20.080478 19.655028)
			(size 0.4318 0.4318)
			(layers "F.Cu" "F.Mask" "F.Paste")
			(net "GND")
		)
		(pad "DR68" smd circle
			(at 21.797518 19.655028)
			(size 0.4318 0.4318)
			(layers "F.Cu" "F.Mask" "F.Paste")
			(net "GND")
		)
		(pad "DR70" smd circle
			(at 23.514558 19.655028)
			(size 0.4318 0.4318)
			(layers "F.Cu" "F.Mask" "F.Paste")
			(net "GND")
		)
		(pad "DR72" smd circle
			(at 25.231598 19.655028)
			(size 0.4318 0.4318)
			(layers "F.Cu" "F.Mask" "F.Paste")
			(net "GND")
		)
		(pad "DR74" smd circle
			(at 26.948384 19.655028)
			(size 0.4318 0.4318)
			(layers "F.Cu" "F.Mask" "F.Paste")
			(net "GND")
		)
		(pad "DR76" smd circle
			(at 28.665424 19.655028)
			(size 0.4318 0.4318)
			(layers "F.Cu" "F.Mask" "F.Paste")
			(net "GND")
		)
		(pad "DR78" smd circle
			(at 30.382464 19.655028)
			(size 0.4318 0.4318)
			(layers "F.Cu" "F.Mask" "F.Paste")
			(net "GND")
		)
		(pad "DR80" smd circle
			(at 32.099504 19.655028)
			(size 0.4318 0.4318)
			(layers "F.Cu" "F.Mask" "F.Paste")
			(net "M_D_DQ<22>")
		)
		(pad "DR82" smd circle
			(at 33.816544 19.655028)
			(size 0.4318 0.4318)
			(layers "F.Cu" "F.Mask" "F.Paste")
			(net "M_D_DQ<19>")
		)
		(pad "DR84" smd circle
			(at 35.533584 19.655028)
			(size 0.4318 0.4318)
			(layers "F.Cu" "F.Mask" "F.Paste")
			(net "M_D_DQ<14>")
		)
		(pad "DT3" smd circle
			(at -35.533584 21.950172)
			(size 0.4318 0.4318)
			(layers "F.Cu" "F.Mask" "F.Paste")
			(net "GND")
		)
		(pad "DT5" smd circle
			(at -33.816544 21.950172)
			(size 0.4318 0.4318)
			(layers "F.Cu" "F.Mask" "F.Paste")
			(net "P3E_CPU0_PE1_PCH_TXN<8>")
		)
		(pad "DT7" smd circle
			(at -32.099504 21.950172)
			(size 0.4318 0.4318)
			(layers "F.Cu" "F.Mask" "F.Paste")
			(net "P3E_CPU0_PE1_PCH_TXP<12>")
		)
		(pad "DT9" smd circle
			(at -30.382464 21.950172)
			(size 0.4318 0.4318)
			(layers "F.Cu" "F.Mask" "F.Paste")
			(net "P3E_CPU0_PE3_OCP_TXP<6>")
		)
		(pad "DT11" smd circle
			(at -28.665424 21.950172)
			(size 0.4318 0.4318)
			(layers "F.Cu" "F.Mask" "F.Paste")
			(net "P3E_CPU0_PE1_PCH_RXN<10>")
		)
		(pad "DT13" smd circle
			(at -26.948384 21.950172)
			(size 0.4318 0.4318)
			(layers "F.Cu" "F.Mask" "F.Paste")
			(net "P3E_CPU0_PE1_PCH_RXN<11>")
		)
		(pad "DT15" smd circle
			(at -25.231598 21.950172)
			(size 0.4318 0.4318)
			(layers "F.Cu" "F.Mask" "F.Paste")
			(net "P3E_CPU0_PE1_PCH_RXP<15>")
		)
		(pad "DT17" smd circle
			(at -23.514558 21.950172)
			(size 0.4318 0.4318)
			(layers "F.Cu" "F.Mask" "F.Paste")
			(net "GND")
		)
		(pad "DT19" smd circle
			(at -21.797518 21.950172)
			(size 0.4318 0.4318)
			(layers "F.Cu" "F.Mask" "F.Paste")
			(net "P3E_CPU0_PE3_OCP_RXN<3>")
		)
		(pad "DT21" smd circle
			(at -20.080478 21.950172)
			(size 0.4318 0.4318)
			(layers "F.Cu" "F.Mask" "F.Paste")
			(net "TP_CPU0_UPI2_RSVD_CC12")
		)
		(pad "DT23" smd circle
			(at -18.363438 21.950172)
			(size 0.4318 0.4318)
			(layers "F.Cu" "F.Mask" "F.Paste")
			(net "M_D_DQS_DP<7>")
		)
		(pad "DT25" smd circle
			(at -16.646398 21.950172)
			(size 0.4318 0.4318)
			(layers "F.Cu" "F.Mask" "F.Paste")
			(net "M_D_DQ<61>")
		)
		(pad "DT27" smd circle
			(at -14.929612 21.950172)
			(size 0.4318 0.4318)
			(layers "F.Cu" "F.Mask" "F.Paste")
			(net "M_D_DQ<51>")
		)
		(pad "DT29" smd circle
			(at -13.212572 21.950172)
			(size 0.4318 0.4318)
			(layers "F.Cu" "F.Mask" "F.Paste")
			(net "M_D_DQS_DP<6>")
		)
		(pad "DT31" smd circle
			(at -11.495532 21.950172)
			(size 0.4318 0.4318)
			(layers "F.Cu" "F.Mask" "F.Paste")
			(net "M_D_DQ<53>")
		)
		(pad "DT33" smd circle
			(at -9.778492 21.950172)
			(size 0.4318 0.4318)
			(layers "F.Cu" "F.Mask" "F.Paste")
			(net "M_D_DQ<43>")
		)
		(pad "DT35" smd circle
			(at -8.061452 21.950172)
			(size 0.4318 0.4318)
			(layers "F.Cu" "F.Mask" "F.Paste")
			(net "M_D_DQS_DP<5>")
		)
		(pad "DT37" smd circle
			(at -6.344412 21.950172)
			(size 0.4318 0.4318)
			(layers "F.Cu" "F.Mask" "F.Paste")
			(net "M_D_DQ<45>")
		)
		(pad "DT39" smd circle
			(at -4.627626 21.950172)
			(size 0.4318 0.4318)
			(layers "F.Cu" "F.Mask" "F.Paste")
			(net "M_E_DQ<35>")
		)
		(pad "DT41" smd circle
			(at -2.910586 21.950172)
			(size 0.4318 0.4318)
			(layers "F.Cu" "F.Mask" "F.Paste")
			(net "M_E_DQS_DP<4>")
		)
		(pad "DT45" smd circle
			(at 2.052066 20.150074)
			(size 0.4318 0.4318)
			(layers "F.Cu" "F.Mask" "F.Paste")
			(net "M_E_CS_N<6>")
		)
		(pad "DT47" smd circle
			(at 3.769106 20.150074)
			(size 0.4318 0.4318)
			(layers "F.Cu" "F.Mask" "F.Paste")
			(net "M_E_C<2>")
		)
		(pad "DT49" smd circle
			(at 5.485892 20.150074)
			(size 0.4318 0.4318)
			(layers "F.Cu" "F.Mask" "F.Paste")
			(net "M_E_ODT<2>")
		)
		(pad "DT51" smd circle
			(at 7.202932 20.150074)
			(size 0.4318 0.4318)
			(layers "F.Cu" "F.Mask" "F.Paste")
			(net "M_E_MA<13>")
		)
		(pad "DT53" smd circle
			(at 8.919972 20.150074)
			(size 0.4318 0.4318)
			(layers "F.Cu" "F.Mask" "F.Paste")
			(net "M_E_CLK_DP<1>")
		)
		(pad "DT55" smd circle
			(at 10.637012 20.150074)
			(size 0.4318 0.4318)
			(layers "F.Cu" "F.Mask" "F.Paste")
			(net "M_E_MA<10>")
		)
		(pad "DT57" smd circle
			(at 12.354052 20.150074)
			(size 0.4318 0.4318)
			(layers "F.Cu" "F.Mask" "F.Paste")
			(net "M_E_CLK_DN<3>")
		)
		(pad "DT59" smd circle
			(at 14.071092 20.150074)
			(size 0.4318 0.4318)
			(layers "F.Cu" "F.Mask" "F.Paste")
			(net "M_E_MA<4>")
		)
		(pad "DT61" smd circle
			(at 15.787878 20.150074)
			(size 0.4318 0.4318)
			(layers "F.Cu" "F.Mask" "F.Paste")
			(net "M_E_ALERT_N")
		)
		(pad "DT63" smd circle
			(at 17.504918 20.150074)
			(size 0.4318 0.4318)
			(layers "F.Cu" "F.Mask" "F.Paste")
			(net "M_D_MA<12>")
		)
		(pad "DT65" smd circle
			(at 19.221958 20.150074)
			(size 0.4318 0.4318)
			(layers "F.Cu" "F.Mask" "F.Paste")
			(net "GND")
		)
		(pad "DT67" smd circle
			(at 20.938998 20.150074)
			(size 0.4318 0.4318)
			(layers "F.Cu" "F.Mask" "F.Paste")
			(net "M_E_DQS_DP<17>")
		)
		(pad "DT69" smd circle
			(at 22.656038 20.150074)
			(size 0.4318 0.4318)
			(layers "F.Cu" "F.Mask" "F.Paste")
			(net "GND")
		)
		(pad "DT71" smd circle
			(at 24.373078 20.150074)
			(size 0.4318 0.4318)
			(layers "F.Cu" "F.Mask" "F.Paste")
			(net "TP_CPU0_RSVD_27")
		)
		(pad "DT73" smd circle
			(at 26.090118 20.150074)
			(size 0.4318 0.4318)
			(layers "F.Cu" "F.Mask" "F.Paste")
			(net "M_D_DQ<27>")
		)
		(pad "DT75" smd circle
			(at 27.806904 20.150074)
			(size 0.4318 0.4318)
			(layers "F.Cu" "F.Mask" "F.Paste")
			(net "M_D_DQS_DP<3>")
		)
		(pad "DT77" smd circle
			(at 29.523944 20.150074)
			(size 0.4318 0.4318)
			(layers "F.Cu" "F.Mask" "F.Paste")
			(net "M_D_DQ<29>")
		)
		(pad "DT79" smd circle
			(at 31.240984 20.150074)
			(size 0.4318 0.4318)
			(layers "F.Cu" "F.Mask" "F.Paste")
			(net "GND")
		)
		(pad "DT81" smd circle
			(at 32.958024 20.150074)
			(size 0.4318 0.4318)
			(layers "F.Cu" "F.Mask" "F.Paste")
			(net "M_D_DQ<18>")
		)
		(pad "DT83" smd circle
			(at 34.675064 20.150074)
			(size 0.4318 0.4318)
			(layers "F.Cu" "F.Mask" "F.Paste")
			(net "GND")
		)
		(pad "DT85" smd custom
			(at 36.392104 20.150074 270)
			(size 0.10795 0.10795)
			(layers "F.Cu" "F.Mask" "F.Paste")
			(net "GND")
			(options
				(clearance outline)
				(anchor circle)
			)
			(primitives
				(gr_poly
					(pts
						(arc
							(start 0.2159 -0.0381)
							(mid 0 -0.254)
							(end -0.2159 -0.0381)
						)
						(arc
							(start -0.2159 0.0381)
							(mid 0 0.254)
							(end 0.2159 0.0381)
						)
					)
					(width 0)
					(fill yes)
				)
			)
		)
		(pad "DU2" smd custom
			(at -36.392104 22.445726 90)
			(size 0.10795 0.10795)
			(layers "F.Cu" "F.Mask" "F.Paste")
			(net "P3E_CPU0_PE1_PCH_TXP<9>")
			(options
				(clearance outline)
				(anchor circle)
			)
			(primitives
				(gr_poly
					(pts
						(arc
							(start 0.2159 -0.0381)
							(mid 0 -0.254)
							(end -0.2159 -0.0381)
						)
						(arc
							(start -0.2159 0.0381)
							(mid 0 0.254)
							(end 0.2159 0.0381)
						)
					)
					(width 0)
					(fill yes)
				)
			)
		)
		(pad "DU4" smd circle
			(at -34.675064 22.445726)
			(size 0.4318 0.4318)
			(layers "F.Cu" "F.Mask" "F.Paste")
			(net "P3E_CPU0_PE1_PCH_TXP<10>")
		)
		(pad "DU6" smd circle
			(at -32.958024 22.445726)
			(size 0.4318 0.4318)
			(layers "F.Cu" "F.Mask" "F.Paste")
			(net "P3E_CPU0_PE1_PCH_TXN<11>")
		)
		(pad "DU8" smd circle
			(at -31.240984 22.445726)
			(size 0.4318 0.4318)
			(layers "F.Cu" "F.Mask" "F.Paste")
			(net "P3E_CPU0_PE3_OCP_TXN<6>")
		)
		(pad "DU10" smd circle
			(at -29.523944 22.445726)
			(size 0.4318 0.4318)
			(layers "F.Cu" "F.Mask" "F.Paste")
			(net "GND")
		)
		(pad "DU12" smd circle
			(at -27.806904 22.445726)
			(size 0.4318 0.4318)
			(layers "F.Cu" "F.Mask" "F.Paste")
			(net "P3E_CPU0_PE1_PCH_RXP<12>")
		)
		(pad "DU14" smd circle
			(at -26.090118 22.445726)
			(size 0.4318 0.4318)
			(layers "F.Cu" "F.Mask" "F.Paste")
			(net "GND")
		)
		(pad "DU16" smd circle
			(at -24.373078 22.445726)
			(size 0.4318 0.4318)
			(layers "F.Cu" "F.Mask" "F.Paste")
			(net "P3E_CPU0_PE1_PCH_RXN<15>")
		)
		(pad "DU18" smd circle
			(at -22.656038 22.445726)
			(size 0.4318 0.4318)
			(layers "F.Cu" "F.Mask" "F.Paste")
			(net "P3E_CPU0_PE3_OCP_RXP<1>")
		)
		(pad "DU20" smd circle
			(at -20.938998 22.445726)
			(size 0.4318 0.4318)
			(layers "F.Cu" "F.Mask" "F.Paste")
			(net "PVCCIO_CPU0")
		)
		(pad "DU22" smd circle
			(at -19.221958 22.445726)
			(size 0.4318 0.4318)
			(layers "F.Cu" "F.Mask" "F.Paste")
			(net "GND")
		)
		(pad "DU24" smd circle
			(at -17.504918 22.445726)
			(size 0.4318 0.4318)
			(layers "F.Cu" "F.Mask" "F.Paste")
			(net "M_D_DQ<57>")
		)
		(pad "DU26" smd circle
			(at -15.787878 22.445726)
			(size 0.4318 0.4318)
			(layers "F.Cu" "F.Mask" "F.Paste")
			(net "GND")
		)
		(pad "DU28" smd circle
			(at -14.071092 22.445726)
			(size 0.4318 0.4318)
			(layers "F.Cu" "F.Mask" "F.Paste")
			(net "M_D_DQ<55>")
		)
		(pad "DU30" smd circle
			(at -12.354052 22.445726)
			(size 0.4318 0.4318)
			(layers "F.Cu" "F.Mask" "F.Paste")
			(net "M_D_DQ<49>")
		)
		(pad "DU32" smd circle
			(at -10.637012 22.445726)
			(size 0.4318 0.4318)
			(layers "F.Cu" "F.Mask" "F.Paste")
			(net "GND")
		)
		(pad "DU34" smd circle
			(at -8.919972 22.445726)
			(size 0.4318 0.4318)
			(layers "F.Cu" "F.Mask" "F.Paste")
			(net "M_D_DQ<47>")
		)
		(pad "DU36" smd circle
			(at -7.202932 22.445726)
			(size 0.4318 0.4318)
			(layers "F.Cu" "F.Mask" "F.Paste")
			(net "M_D_DQ<41>")
		)
		(pad "DU38" smd circle
			(at -5.485892 22.445726)
			(size 0.4318 0.4318)
			(layers "F.Cu" "F.Mask" "F.Paste")
			(net "GND")
		)
	)
)
